FILE_TYPE = MULTI_PHYS_TABLE;
PART 'TTL1G32_A'
{===============================================================================================================================================================================}
:VALUE       | PACK_TYPE | MATERIAL | PART_NUMBER     = EnvComp | PART_NUMBER  | JEDEC_TYPE | CLASS | DESCRIPTION             | HEIGHT     | COMPONENT_TYPE | LEAD_LENGTH | LPID  | SPEED_URL | Status |RPL| AML | Bus_Unit | Days ;
{===============================================================================================================================================================================}
'74LVC1G32'  | 'SOT'     | 'IC'     | 'E60229-001'(!) = 'YES;YES;UNK;UNK;ok;VLD' | 'E60229-001' | 'SSOP5_53_65MA'| 'IC'| 'IC,LOG,GATES,SC70,SGL,2-INPUT,POS-OR'  | '0.043 IN' | 'SMALLSMT'     | ''          | '374' | 'http://speed.intel.com:8081/speed/module/pdm/item/pdm_item_detail_direct.asp?item_cde=E60229-001&item_rev=01&url_param=unused' | 'Preliminary' | 'NO' | '1' | 'ECG' | '???' 
'74LVC1G32'  | 'SOT'     | 'EMPTY'  | 'E60229-001'(!) = 'YES;YES;UNK;UNK;ok;VLD' | 'E60229-001' | 'SSOP5_53_65MA'| 'IO'| 'IC,LOG,GATES,SC70,SGL,2-INPUT,POS-OR'  | '0.043 IN' | 'SMALLSMT'     | ''          | '374' | 'http://speed.intel.com:8081/speed/module/pdm/item/pdm_item_detail_direct.asp?item_cde=E60229-001&item_rev=01&url_param=unused' | 'Preliminary' | 'NO' | '1' | 'ECG' | '???' 
END_PART
END.
